# BASEBOARD_FAB2 (Tioga Pass) — schematic netlist excerpt (pin names and nets, part order shuffled) for the footprints in the layout excerpt that follows; sources: Cadence DE-HDL packaged netlist, KiCad conversion of Wiwynn_Tioga_Pass_MB.brd

R7A8  RES  2.26K 1.0% CHIP  pkg 0402  page 218 : A = VR_PVDDQ_DEF_XADDR2 ; B = GND
C3W3  CAP_A  22.0UF 4V 20% X6S  pkg 0603V  page 76 : A = PVCCMCP_CPU1 ; B = GND
R2P3  RES  4.75K 1% CHIP  pkg 0402  page 170 : A = P3V3_STBY ; B = IRQ_FORCE_NM_THROTTLE_R_N

(kicad_pcb
	(version 20260206)
	(generator "pcbnew")
	(generator_version "10.0")
	(general
		(thickness 1.6)
		(legacy_teardrops no)
	)
	(paper "A4")
	(title_block
		(title "Wiwynn_Tioga_Pass_MB.brd")
		(comment 1 "Tioga Pass / footprints 1989-1991 of 4770")
	)
	(layers
		(0 "F.Cu" signal "TOP")
		(4 "In1.Cu" signal "L2GND")
		(6 "In2.Cu" signal "L3")
		(8 "In3.Cu" signal "L4GND")
		(10 "In4.Cu" signal "L5")
		(12 "In5.Cu" signal "L6GND")
		(14 "In6.Cu" signal "L7VCC")
		(16 "In7.Cu" signal "L8VCC")
		(18 "In8.Cu" signal "L9GND")
		(20 "In9.Cu" signal "L10")
		(22 "In10.Cu" signal "L11GND")
		(24 "In11.Cu" signal "L12")
		(26 "In12.Cu" signal "L13GND")
		(2 "B.Cu" signal "BOTTOM")
		(9 "F.Adhes" user "F.Adhesive")
		(11 "B.Adhes" user "B.Adhesive")
		(13 "F.Paste" user "Package Geometry/Pastemask Top")
		(15 "B.Paste" user "Package Geometry/Pastemask Bottom")
		(5 "F.SilkS" user "Ref Des/Silkscreen Top")
		(7 "B.SilkS" user "Ref Des/Silkscreen Bottom")
		(1 "F.Mask" user "Board Geometry/Soldermask Top")
		(3 "B.Mask" user "Board Geometry/Soldermask Bottom")
		(17 "Dwgs.User" user "User.Drawings")
		(19 "Cmts.User" user "User.Comments")
		(21 "Eco1.User" user "User.Eco1")
		(23 "Eco2.User" user "User.Eco2")
		(25 "Edge.Cuts" user "Board Geometry/Outline")
		(27 "Margin" user)
		(31 "F.CrtYd" user "Package Geometry/Place Bound Top")
		(29 "B.CrtYd" user "Package Geometry/Place Bound Bottom")
		(35 "F.Fab" user "Ref Des/Assembly Top")
		(33 "B.Fab" user "Ref Des/Assembly Bottom")
	)
	(footprint ""
		(layer "F.Cu")
		(at 355.656388 -139.87399 180)
		(property "Reference" "R7A8"
			(at 0 0 180)
			(layer "F.SilkS")
			(hide yes)
			(effects
				(font
					(size 1.27 1.27)
				)
			)
		)
		(property "Value" ""
			(at 0 0 180)
			(layer "F.Fab")
			(effects
				(font
					(size 1.27 1.27)
				)
			)
		)
		(duplicate_pad_numbers_are_jumpers no)
		(fp_poly
			(pts
				(xy -0.2794 -0.1016) (xy 0.2794 -0.1016) (xy 0.2794 0.9906) (xy -0.2794 0.9906)
			)
			(stroke
				(width 0)
				(type default)
			)
			(fill no)
			(layer "F.CrtYd")
		)
		(fp_line
			(start 0.2794 0.9906)
			(end 0.2794 -0.1016)
			(stroke
				(width 0.1)
				(type default)
			)
			(layer "F.Fab")
		)
		(fp_line
			(start 0.2794 -0.1016)
			(end -0.2794 -0.1016)
			(stroke
				(width 0.1)
				(type default)
			)
			(layer "F.Fab")
		)
		(fp_line
			(start -0.2794 0.9906)
			(end 0.2794 0.9906)
			(stroke
				(width 0.1)
				(type default)
			)
			(layer "F.Fab")
		)
		(fp_line
			(start -0.2794 -0.1016)
			(end -0.2794 0.9906)
			(stroke
				(width 0.1)
				(type default)
			)
			(layer "F.Fab")
		)
		(pad "1" smd rect
			(at 0 0 180)
			(size 0.508 0.508)
			(layers "F.Cu" "F.Mask" "F.Paste")
			(net "VR_PVDDQ_DEF_XADDR2")
		)
		(pad "2" smd rect
			(at 0 0.889 180)
			(size 0.508 0.508)
			(layers "F.Cu" "F.Mask" "F.Paste")
			(net "GND")
		)
		(zone
			(layer "F.Cu")
			(hatch none 0.5)
			(connect_pads
				(clearance 0)
			)
			(min_thickness 0.25)
			(keepout
				(tracks not_allowed)
				(vias allowed)
				(pads allowed)
				(copperpour not_allowed)
				(footprints allowed)
			)
			(placement
				(enabled no)
				(sheetname "")
			)
			(fill
				(thermal_gap 0.5)
				(thermal_bridge_width 0.5)
				(island_removal_mode 0)
			)
			(polygon
				(pts
					(xy 355.910388 -140.50899) (xy 355.402388 -140.50899) (xy 355.402388 -140.12799) (xy 355.910388 -140.12799)
				)
			)
		)
		(zone
			(layer "F.Cu")
			(hatch none 0.5)
			(connect_pads
				(clearance 0)
			)
			(min_thickness 0.25)
			(keepout
				(tracks allowed)
				(vias not_allowed)
				(pads allowed)
				(copperpour not_allowed)
				(footprints allowed)
			)
			(placement
				(enabled no)
				(sheetname "")
			)
			(fill
				(thermal_gap 0.5)
				(thermal_bridge_width 0.5)
				(island_removal_mode 0)
			)
			(polygon
				(pts
					(xy 355.910388 -140.12799) (xy 355.402388 -140.12799) (xy 355.402388 -140.50899) (xy 355.910388 -140.50899)
				)
			)
		)
	)
	(footprint ""
		(layer "F.Cu")
		(at 418.7571 -87.6935 180)
		(property "Reference" "R2P3"
			(at 0 0 180)
			(layer "F.SilkS")
			(hide yes)
			(effects
				(font
					(size 1.27 1.27)
				)
			)
		)
		(property "Value" ""
			(at 0 0 180)
			(layer "F.Fab")
			(effects
				(font
					(size 1.27 1.27)
				)
			)
		)
		(duplicate_pad_numbers_are_jumpers no)
		(fp_poly
			(pts
				(xy -0.2794 -0.1016) (xy 0.2794 -0.1016) (xy 0.2794 0.9906) (xy -0.2794 0.9906)
			)
			(stroke
				(width 0)
				(type default)
			)
			(fill no)
			(layer "F.CrtYd")
		)
		(fp_line
			(start 0.2794 0.9906)
			(end 0.2794 -0.1016)
			(stroke
				(width 0.1)
				(type default)
			)
			(layer "F.Fab")
		)
		(fp_line
			(start 0.2794 -0.1016)
			(end -0.2794 -0.1016)
			(stroke
				(width 0.1)
				(type default)
			)
			(layer "F.Fab")
		)
		(fp_line
			(start -0.2794 0.9906)
			(end 0.2794 0.9906)
			(stroke
				(width 0.1)
				(type default)
			)
			(layer "F.Fab")
		)
		(fp_line
			(start -0.2794 -0.1016)
			(end -0.2794 0.9906)
			(stroke
				(width 0.1)
				(type default)
			)
			(layer "F.Fab")
		)
		(pad "1" smd rect
			(at 0 0 180)
			(size 0.508 0.508)
			(layers "F.Cu" "F.Mask" "F.Paste")
			(net "P3V3_STBY")
		)
		(pad "2" smd rect
			(at 0 0.889 180)
			(size 0.508 0.508)
			(layers "F.Cu" "F.Mask" "F.Paste")
			(net "IRQ_FORCE_NM_THROTTLE_R_N")
		)
		(zone
			(layer "F.Cu")
			(hatch none 0.5)
			(connect_pads
				(clearance 0)
			)
			(min_thickness 0.25)
			(keepout
				(tracks not_allowed)
				(vias allowed)
				(pads allowed)
				(copperpour not_allowed)
				(footprints allowed)
			)
			(placement
				(enabled no)
				(sheetname "")
			)
			(fill
				(thermal_gap 0.5)
				(thermal_bridge_width 0.5)
				(island_removal_mode 0)
			)
			(polygon
				(pts
					(xy 419.0111 -88.3285) (xy 418.5031 -88.3285) (xy 418.5031 -87.9475) (xy 419.0111 -87.9475)
				)
			)
		)
		(zone
			(layer "F.Cu")
			(hatch none 0.5)
			(connect_pads
				(clearance 0)
			)
			(min_thickness 0.25)
			(keepout
				(tracks allowed)
				(vias not_allowed)
				(pads allowed)
				(copperpour not_allowed)
				(footprints allowed)
			)
			(placement
				(enabled no)
				(sheetname "")
			)
			(fill
				(thermal_gap 0.5)
				(thermal_bridge_width 0.5)
				(island_removal_mode 0)
			)
			(polygon
				(pts
					(xy 419.0111 -87.9475) (xy 418.5031 -87.9475) (xy 418.5031 -88.3285) (xy 419.0111 -88.3285)
				)
			)
		)
	)
	(footprint ""
		(layer "F.Cu")
		(at 104.442768 -79.6036 180)
		(property "Reference" "C3W3"
			(at 0.97536 0.76708 90)
			(unlocked yes)
			(layer "F.SilkS")
			(effects
				(font
					(size 0.4064 0.254)
					(thickness 0.1524)
				)
			)
		)
		(property "Value" ""
			(at 0 0 180)
			(layer "F.Fab")
			(effects
				(font
					(size 1.27 1.27)
				)
			)
		)
		(duplicate_pad_numbers_are_jumpers no)
		(fp_poly
			(pts
				(xy -0.4953 -0.2032) (xy 0.4953 -0.2032) (xy 0.4953 1.6002) (xy -0.4953 1.6002)
			)
			(stroke
				(width 0)
				(type default)
			)
			(fill no)
			(layer "F.CrtYd")
		)
		(fp_line
			(start 0.4953 1.6002)
			(end -0.4953 1.6002)
			(stroke
				(width 0.1)
				(type default)
			)
			(layer "F.Fab")
		)
		(fp_line
			(start 0.4953 -0.2032)
			(end 0.4953 1.6002)
			(stroke
				(width 0.1)
				(type default)
			)
			(layer "F.Fab")
		)
		(fp_line
			(start -0.4953 1.6002)
			(end -0.4953 -0.2032)
			(stroke
				(width 0.1)
				(type default)
			)
			(layer "F.Fab")
		)
		(fp_line
			(start -0.4953 -0.2032)
			(end 0.4953 -0.2032)
			(stroke
				(width 0.1)
				(type default)
			)
			(layer "F.Fab")
		)
		(pad "1" smd rect
			(at 0 0 180)
			(size 0.762 0.889)
			(layers "F.Cu" "F.Mask" "F.Paste")
			(net "PVCCMCP_CPU1")
		)
		(pad "2" smd rect
			(at 0 1.397 180)
			(size 0.762 0.889)
			(layers "F.Cu" "F.Mask" "F.Paste")
			(net "GND")
		)
		(zone
			(layer "F.Cu")
			(hatch none 0.5)
			(connect_pads
				(clearance 0)
			)
			(min_thickness 0.25)
			(keepout
				(tracks not_allowed)
				(vias allowed)
				(pads allowed)
				(copperpour not_allowed)
				(footprints allowed)
			)
			(placement
				(enabled no)
				(sheetname "")
			)
			(fill
				(thermal_gap 0.5)
				(thermal_bridge_width 0.5)
				(island_removal_mode 0)
			)
			(polygon
				(pts
					(xy 104.823768 -80.0481) (xy 104.061768 -80.0481) (xy 104.061768 -80.5561) (xy 104.823768 -80.5561)
				)
			)
		)
	)
)
